FILE_TYPE = CONNECTIVITY;
{Allegro Design Entry HDL 17.2-2016 S081 (4005846) 1/11/2022}
"PAGE_NUMBER" = 49;
0"NC";
1"P5V_AUX\g";
2"P3V3_AUX\g";
3"P3V3_AUX\g";
4"P3V3_AUX\g";
5"P3V3_AUX\g";
6"P5V_AUX\g";
7"GND\g";
8"GND\g";
9"GND\g";
10"GND\g";
11"GND\g";
12"GND\g";
13"GND\g";
14"GND\g";
15"GND\g";
16"GND\g";
17"GND\g";
18"GND\g";
19"ID_LED_D_P3V3_AUX";
20"ID_LED_P3V3_AUX";
21"FM_ID_R_LED";
22"ID_LED_BUF";
23"PCH_BEEP_LED";
24"HDD_LED_P5V_AUX";
25"BMC_ID_BEEP_SEL";
26"FM_UARTSW_LSB_R1_N";
27"FM_UARTSW_MSB_N";
28"PWR_LED_BUF_N_R";
29"HDD_LED_BUF_R";
30"PWR_LED_P5V_AUX";
31"HDD_LED_BUF";
32"HDD_LED_N";
33"FM_UARTSW_MSB_R1_N";
34"BEEP_LED";
35"FM_ID_LED";
36"PWR_LED_BUF_N";
37"HDD_LED_BUF";
38"FM_UARTSW_LSB_N";
39"PWR_LED";
40"PWR_LED_BUF_N";
%"UNIVERSAL_GND"
"1","(-7775,4775)","0","logical_power","I1";
;
CDS_LIB"logical_power"
HDL_POWER"GND";
"A"11;
%"74LVC1G126SE7"
"1","(-7775,5150)","0","pure_quanta","I11";
;
PART_TYPE"SMLF"
VALUE"74LVC1G126SE-7"
MATERIAL"IC"
PART_NUMBER"AL1G0126009"
CDS_LMAN_SYM_OUTLINE"-100,100,100,-100"
NEEDS_NO_SIZE"TRUE"
CDS_LIB"pure_quanta"
$LOCATION"U8"
CDS_LOCATION"U8"
$SEC"1"
CDS_SEC"1";
"OE"
$PN"1"25;
"GND"
$PN"3"11;
"VCC"
$PN"5"3;
"Y"
$PN"4"34;
"A"
$PN"2"23;
%"UNIVERSAL_GND"
"1","(-7875,5475)","0","logical_power","I12";
;
CDS_LIB"logical_power"
HDL_POWER"GND";
"A"10;
%"Q_CAP"
"1","(-7875,5700)","2","pure_quanta","I13";
;
VALUE"0.1UF"
PACK_TYPE"0402"
MATERIAL"X7R"
VOLTAGE"25V"
PART_NUMBER"CH4104K1B00"
TOLERANCE"10%"
CDS_LIB"pure_quanta"
$LOCATION"C274"
CDS_LOCATION"C274"
$SEC"1"
CDS_SEC"1";
"B"
$PN"2"10;
"A"
$PN"1"3;
%"VCCAUX15"
"1","(-7875,5900)","0","logical_power","I14";
;
HDL_POWER"P3V3_AUX"
CDS_LIB"logical_power";
"A"3;
%"UNIVERSAL_GND"
"1","(-5900,5400)","0","logical_power","I16";
;
HDL_POWER"GND"
CDS_LIB"logical_power";
"A"18;
%"VCCAUX15"
"1","(-5900,5875)","0","logical_power","I17";
;
HDL_POWER"P3V3_AUX"
CDS_LIB"logical_power";
"A"2;
%"UNIVERSAL_GND"
"1","(-7950,825)","0","logical_power","I21";
;
HDL_POWER"GND"
CDS_LIB"logical_power";
"A"15;
%"Q_RES"
"2","(-7950,1075)","0","pure_quanta","I22";
;
PACK_TYPE"0402LF"
PART_NUMBER"CS28202JB05"
MATERIAL"CHIP"
WATTAGE"1/16W"
TOLERANCE"5%"
VALUE"8.2K"
CDS_LIB"pure_quanta"
LOCATION"R839"
$SEC"1"
CDS_SEC"1";
"A"
$PN"1"39;
"B"
$PN"2"15;
%"UNIVERSAL_GND"
"1","(-7425,1100)","0","logical_power","I23";
;
CDS_LIB"logical_power"
HDL_POWER"GND";
"A"14;
%"MOSFET_DUAL_6P"
"1","(-7050,1300)","6","pure_quanta","I24";
;
MATERIAL"IC"
PART_NUMBER"BAM70020047"
PART_TYPE"SMLF"
VALUE"2N7002KDW"
NEEDS_NO_SIZE"TRUE"
CDS_LMAN_SYM_OUTLINE"-150,100,150,-100"
CDS_LIB"pure_quanta"
LOCATION"Q12"
$SEC"1"
CDS_SEC"1";
"D2"
$PN"3"31;
"D1"
$PN"6"40;
"S2"
$PN"4"13;
"S1"
$PN"1"14;
"G2"
$PN"5"32;
"G1"
$PN"2"39;
%"UNIVERSAL_GND"
"1","(-6350,825)","0","logical_power","I25";
;
CDS_LIB"logical_power"
HDL_POWER"GND";
"A"12;
%"Q_RES"
"2","(-6350,1025)","0","pure_quanta","I26";
;
MATERIAL"EMPTY"
PART_NUMBER"CS28202JB05"
PACK_TYPE"0402LF"
VALUE"8.2K"
TOLERANCE"5%"
WATTAGE"1/16W"
CDS_LIB"pure_quanta"
LOCATION"R619"
$SEC"1"
CDS_SEC"1";
"A"
$PN"1"32;
"B"
$PN"2"12;
%"UNIVERSAL_GND"
"1","(-6575,1100)","0","logical_power","I27";
;
CDS_LIB"logical_power"
HDL_POWER"GND";
"A"13;
%"UNIVERSAL_GND"
"1","(-6925,4425)","0","logical_power","I3";
;
CDS_LIB"logical_power"
HDL_POWER"GND";
"A"8;
%"VCCAUX15"
"1","(-3200,5875)","0","logical_power","I31";
;
HDL_POWER"P3V3_AUX"
CDS_LIB"logical_power";
"A"4;
%"Q_RES"
"1","(-8075,2900)","0","pure_quanta","I34";
;
MATERIAL"CHIP"
VALUE"33.2"
TOLERANCE"1%"
PART_NUMBER"CS03322FB03"
CDS_LIB"pure_quanta"
WATTAGE"1/16W"
PACK_TYPE"0402LF"
LOCATION"R812"
$SEC"1"
CDS_SEC"1";
"B"
$PN"2"28;
"A"
$PN"1"36;
%"Q_RES"
"1","(-7875,2450)","0","pure_quanta","I35";
;
VALUE"33.2"
MATERIAL"CHIP"
PACK_TYPE"0402LF"
WATTAGE"1/16W"
CDS_LIB"pure_quanta"
PART_NUMBER"CS03322FB03"
TOLERANCE"1%"
LOCATION"R813"
$SEC"1"
CDS_SEC"1";
"B"
$PN"2"29;
"A"
$PN"1"37;
%"Q_RES"
"2","(-7100,3175)","0","pure_quanta","I36";
;
MATERIAL"CHIP"
WATTAGE"1/16W"
VALUE"10K"
PACK_TYPE"0402LF"
TOLERANCE"1%"
CDS_LIB"pure_quanta"
PART_NUMBER"CS31002FB08"
LOCATION"R814"
$SEC"1"
CDS_SEC"1";
"A"
$PN"1"1;
"B"
$PN"2"28;
%"Q_CAP"
"1","(-6925,2150)","0","pure_quanta","I37";
;
VALUE"470PF"
VOLTAGE"50V"
TOLERANCE"10%"
MATERIAL"X7R"
PACK_TYPE"0402"
PART_NUMBER"TMP_QCH14706KB18"
CDS_LIB"pure_quanta"
LOCATION"C324"
$SEC"1"
CDS_SEC"1";
"B"
$PN"2"17;
"A"
$PN"1"29;
%"Q_CAP"
"1","(-6650,2150)","0","pure_quanta","I38";
;
VALUE"470PF"
PART_NUMBER"TMP_QCH14706KB18"
PACK_TYPE"0402"
MATERIAL"X7R"
TOLERANCE"10%"
VOLTAGE"50V"
CDS_LIB"pure_quanta"
LOCATION"C326"
$SEC"1"
CDS_SEC"1";
"B"
$PN"2"17;
"A"
$PN"1"28;
%"UNIVERSAL_GND"
"1","(-7150,4775)","0","logical_power","I4";
;
HDL_POWER"GND"
CDS_LIB"logical_power";
"A"9;
%"Q_RES"
"2","(-6800,3175)","0","pure_quanta","I40";
;
VALUE"10K"
PART_NUMBER"CS31002FB08"
PACK_TYPE"0402LF"
WATTAGE"1/16W"
TOLERANCE"1%"
MATERIAL"CHIP"
CDS_LIB"pure_quanta"
LOCATION"R815"
$SEC"1"
CDS_SEC"1";
"A"
$PN"1"1;
"B"
$PN"2"29;
%"Q_CAP"
"1","(-5200,2150)","0","pure_quanta","I43";
;
VALUE"0.1UF"
MATERIAL"X7R"
PACK_TYPE"0402"
TOLERANCE"10%"
VOLTAGE"25V"
PART_NUMBER"CH4104K1B00"
CDS_LIB"pure_quanta"
LOCATION"C321"
$SEC"1"
CDS_SEC"1";
"B"
$PN"2"16;
"A"
$PN"1"30;
%"Q_CAP"
"1","(-4975,2150)","0","pure_quanta","I45";
;
MATERIAL"X7R"
TOLERANCE"10%"
PART_NUMBER"CH4104K1B00"
PACK_TYPE"0402"
VALUE"0.1UF"
VOLTAGE"25V"
CDS_LIB"pure_quanta"
LOCATION"C197"
$SEC"1"
CDS_SEC"1";
"B"
$PN"2"16;
"A"
$PN"1"24;
%"UNIVERSAL_GND"
"1","(-4975,1825)","0","logical_power","I46";
;
HDL_POWER"GND"
CDS_LIB"logical_power";
"A"16;
%"UNIVERSAL_POWER"
"1","(-4975,3500)","0","logical_power","I48";
;
HDL_POWER"P5V_AUX"
CDS_LIB"logical_power";
"A"6;
%"UNIVERSAL_GND"
"1","(-6925,1825)","0","logical_power","I49";
;
HDL_POWER"GND"
CDS_LIB"logical_power";
"A"17;
%"MC74VHC1G32DTT1G"
"1","(-6325,4975)","0","pure_quanta","I5";
;
MATERIAL"IC"
PART_TYPE"SMLF"
VALUE"MC74VHC1G32DTT1G"
PART_NUMBER"AL001G32031"
CDS_LMAN_SYM_OUTLINE"-400,275,400,-275"
NEEDS_NO_SIZE"TRUE"
CDS_LIB"pure_quanta"
$LOCATION"U9"
CDS_LOCATION"U9"
$SEC"1"
CDS_SEC"1";
"VCC"
$PN"5"2;
"GND"
$PN"3"8;
"IN_A"
$PN"2"21;
"IN_B"
$PN"1"34;
"OUT_Y"
$PN"4"22;
%"Q_LED"
"1","(-1075,2450)","2","pure_quanta","I50";
;
PART_NUMBER"BEBL0172Z00"
COLOR"LED_BLUE"
PACK_TYPE"SMLF"
MATERIAL"IC"
MANUF_PN"LTST-C281TBKT-5A"
CDS_LIB"pure_quanta"
NEEDS_NO_SIZE"TRUE"
$LOCATION"D19"
CDS_LOCATION"D19"
$SEC"1"
CDS_SEC"1";
"A"
$PN"A"5;
"C"
$PN"C"33;
%"Q_LED"
"1","(-1075,2925)","2","pure_quanta","I51";
;
COLOR"LED_BLUE"
MANUF_PN"LTST-C281TBKT-5A"
PACK_TYPE"SMLF"
MATERIAL"IC"
PART_NUMBER"BEBL0172Z00"
NEEDS_NO_SIZE"TRUE"
CDS_LIB"pure_quanta"
$LOCATION"D18"
CDS_LOCATION"D18"
$SEC"1"
CDS_SEC"1";
"A"
$PN"A"5;
"C"
$PN"C"26;
%"VCCAUX15"
"1","(-800,3525)","0","logical_power","I52";
;
HDL_POWER"P3V3_AUX"
CDS_LIB"logical_power";
"A"5;
%"UNIVERSAL_POWER"
"1","(-7100,3500)","0","logical_power","I58";
;
HDL_POWER"P5V_AUX"
CDS_LIB"logical_power";
"A"1;
%"Q_RES"
"1","(-5200,3175)","1","pure_quanta","I59";
;
WATTAGE"1/16W"
VALUE"220"
TOLERANCE"1%"
PACK_TYPE"0402LF"
PART_NUMBER"CS12202FB04"
MATERIAL"CHIP"
CDS_LIB"pure_quanta"
LOCATION"R568"
$SEC"1"
CDS_SEC"1";
"B"
$PN"2"6;
"A"
$PN"1"30;
%"MOSFET_NCH_DUAL"
"1","(-5125,4850)","0","pure_quanta","I6";
;
VALUE"PJT138K"
PART_NUMBER"BAM138K0003"
MATERIAL"IC"
PART_TYPE"SMLF"
CDS_LIB"pure_quanta"
NEEDS_NO_SIZE"TRUE"
CDS_LMAN_SYM_OUTLINE"-150,150,150,-150"
$LOCATION"Q9"
CDS_LOCATION"Q9"
$SEC"1"
CDS_SEC"1";
"D1"
$PN"6"19;
"G1"
$PN"2"22;
"S1"
$PN"1"7;
%"Q_RES"
"1","(-4975,3175)","1","pure_quanta","I60";
;
VALUE"220"
WATTAGE"1/16W"
MATERIAL"CHIP"
PACK_TYPE"0402LF"
PART_NUMBER"CS12202FB04"
TOLERANCE"1%"
CDS_LIB"pure_quanta"
LOCATION"R569"
$SEC"1"
CDS_SEC"1";
"B"
$PN"2"6;
"A"
$PN"1"24;
%"UNIVERSAL_GND"
"1","(-5075,4500)","0","logical_power","I7";
;
CDS_LIB"logical_power"
HDL_POWER"GND";
"A"7;
%"Q_CAP"
"1","(-5900,5625)","2","pure_quanta","I75";
;
PART_NUMBER"CH4104K1B00"
PACK_TYPE"0402"
MATERIAL"X7R"
VOLTAGE"25V"
VALUE"0.1UF"
TOLERANCE"10%"
CDS_LIB"pure_quanta"
$LOCATION"C276"
CDS_LOCATION"C276"
$SEC"1"
CDS_SEC"1";
"B"
$PN"2"18;
"A"
$PN"1"2;
%"Q_RES"
"1","(-3200,5550)","1","pure_quanta","I79";
;
MATERIAL"CHIP"
VALUE"220"
TOLERANCE"1%"
WATTAGE"1/16W"
PART_NUMBER"CS12202FB04"
PACK_TYPE"0402LF"
CDS_LIB"pure_quanta"
$LOCATION"R43"
CDS_LOCATION"R43"
$SEC"1"
CDS_SEC"1";
"B"
$PN"2"4;
"A"
$PN"1"20;
%"Q_RES"
"2","(-7150,4975)","0","pure_quanta","I8";
;
PACK_TYPE"0402LF"
TOLERANCE"1%"
WATTAGE"1/16W"
MATERIAL"CHIP"
VALUE"10K"
CDS_LIB"pure_quanta"
PART_NUMBER"CS31002FB08"
$LOCATION"R306"
CDS_LOCATION"R306"
$SEC"1"
CDS_SEC"1";
"A"
$PN"1"34;
"B"
$PN"2"9;
%"Q_RES"
"1","(-2275,2925)","0","pure_quanta","I88";
;
PACK_TYPE"0402LF"
WATTAGE"1/16W"
MATERIAL"CHIP"
VALUE"75"
TOLERANCE"1%"
PART_NUMBER"CS07502FB04"
CDS_LIB"pure_quanta"
LOCATION"R283"
$SEC"1"
CDS_SEC"1";
"B"
$PN"2"26;
"A"
$PN"1"38;
%"Q_RES"
"1","(-2275,2450)","0","pure_quanta","I89";
;
TOLERANCE"1%"
VALUE"75"
WATTAGE"1/16W"
PART_NUMBER"CS07502FB04"
PACK_TYPE"0402LF"
MATERIAL"CHIP"
CDS_LIB"pure_quanta"
LOCATION"R284"
$SEC"1"
CDS_SEC"1";
"B"
$PN"2"33;
"A"
$PN"1"27;
%"Q_RES"
"1","(-7775,4575)","0","pure_quanta","I92";
;
VALUE"33.2"
MATERIAL"CHIP"
CDS_LIB"pure_quanta"
WATTAGE"1/16W"
PACK_TYPE"0402LF"
PART_NUMBER"CS03322FB03"
TOLERANCE"1%"
$LOCATION"R390"
CDS_LOCATION"R390"
$SEC"1"
CDS_SEC"1";
"B"
$PN"2"21;
"A"
$PN"1"35;
%"Q_LED"
"1","(-6125,2900)","2","pure_quanta","I94";
;
PART_NUMBER"BEBL0277D00"
MATERIAL"IC"
PACK_TYPE"THLF"
MANUF_PN"HV-312470/260/SUBD-TR1"
COLOR"LED_BLUE"
CDS_LIB"pure_quanta"
NEEDS_NO_SIZE"TRUE"
LOCATION"D14"
$SEC"1"
CDS_SEC"1";
"A"
$PN"A"30;
"C"
$PN"C"28;
%"Q_LED"
"1","(-6150,2450)","2","pure_quanta","I95";
;
COLOR"LED_BLUE"
MANUF_PN"HV-312470/260/SUBD-TR1"
PACK_TYPE"THLF"
PART_NUMBER"BEBL0277D00"
MATERIAL"IC"
NEEDS_NO_SIZE"TRUE"
CDS_LIB"pure_quanta"
LOCATION"D15"
$SEC"1"
CDS_SEC"1";
"A"
$PN"A"24;
"C"
$PN"C"29;
%"Q_LED"
"1","(-4175,5250)","2","pure_quanta","I97";
;
PACK_TYPE"THLF"
MANUF_PN"LTL-R42FSFADH213T"
COLOR"LED_YELLOW"
PART_NUMBER"BEYL0182D00"
MATERIAL"IC"
NEEDS_NO_SIZE"TRUE"
CDS_LIB"pure_quanta"
LOCATION"D13"
$SEC"1"
CDS_SEC"1";
"A"
$PN"A"20;
"C"
$PN"C"19;
END.
